# S9S_MB_2U (Grand Teton) — schematic netlist excerpt (pin names and nets, part order shuffled) for the footprints in the layout excerpt that follows; sources: Cadence DE-HDL packaged netlist, KiCad conversion of 03242023_DA0F0TMBIJ0_F0T_Motherboard_J_brd_V01_OCP.brd

PR286  Q_RES  8.87K 1% EMPTY  pkg 0402LF  page 288 : A = PVCCIN_CPU1_LSET7 ; B = GND
C1003  Q_CAP  10UF 6.3V 20% X6S  pkg C0402  page 74 : A = PVCCIN_CPU0 ; B = GND

(kicad_pcb
	(version 20260206)
	(generator "pcbnew")
	(generator_version "10.0")
	(general
		(thickness 1.6)
		(legacy_teardrops no)
	)
	(paper "A4")
	(title_block
		(title "03242023_DA0F0TMBIJ0_F0T_Motherboard_J_brd_V01_OCP.brd")
		(comment 1 "Grand Teton / footprints 604-605 of 6105")
	)
	(layers
		(0 "F.Cu" signal "TOP")
		(4 "In1.Cu" signal "GND")
		(6 "In2.Cu" signal "IN1")
		(8 "In3.Cu" signal "GND1")
		(10 "In4.Cu" signal "IN2")
		(12 "In5.Cu" signal "GND2")
		(14 "In6.Cu" signal "IN3")
		(16 "In7.Cu" signal "GND3")
		(18 "In8.Cu" signal "VCC")
		(20 "In9.Cu" signal "VCC1")
		(22 "In10.Cu" signal "GND4")
		(24 "In11.Cu" signal "IN4")
		(26 "In12.Cu" signal "GND5")
		(28 "In13.Cu" signal "IN5")
		(30 "In14.Cu" signal "GND6")
		(32 "In15.Cu" signal "IN6")
		(34 "In16.Cu" signal "GND7")
		(2 "B.Cu" signal "BOTTOM")
		(9 "F.Adhes" user "F.Adhesive")
		(11 "B.Adhes" user "B.Adhesive")
		(13 "F.Paste" user "Package Geometry/Pastemask Top")
		(15 "B.Paste" user "Package Geometry/Pastemask Bottom")
		(5 "F.SilkS" user "Ref Des/Silkscreen Top")
		(7 "B.SilkS" user "Ref Des/Silkscreen Bottom")
		(1 "F.Mask" user "Board Geometry/Soldermask Top")
		(3 "B.Mask" user "Board Geometry/Soldermask Bottom")
		(17 "Dwgs.User" user "User.Drawings")
		(19 "Cmts.User" user "User.Comments")
		(21 "Eco1.User" user "User.Eco1")
		(23 "Eco2.User" user "User.Eco2")
		(25 "Edge.Cuts" user "Board Geometry/Outline")
		(27 "Margin" user)
		(31 "F.CrtYd" user "Package Geometry/Place Bound Top")
		(29 "B.CrtYd" user "Package Geometry/Place Bound Bottom")
		(35 "F.Fab" user "Ref Des/Assembly Top")
		(33 "B.Fab" user "Ref Des/Assembly Bottom")
	)
	(footprint ""
		(layer "F.Cu")
		(at 354.270818 -244.03177 90)
		(property "Reference" "C1003"
			(at 0 0 90)
			(layer "F.SilkS")
			(hide yes)
			(effects
				(font
					(size 1.27 1.27)
				)
			)
		)
		(property "Value" ""
			(at 0 0 90)
			(layer "F.Fab")
			(effects
				(font
					(size 1.27 1.27)
				)
			)
		)
		(duplicate_pad_numbers_are_jumpers no)
		(fp_line
			(start 0.7874 -0.4064)
			(end 0.7874 0.4064)
			(stroke
				(width 0.1524)
				(type default)
			)
			(layer "F.SilkS")
		)
		(fp_line
			(start -0.7874 -0.4064)
			(end 0.7874 -0.4064)
			(stroke
				(width 0.1524)
				(type default)
			)
			(layer "F.SilkS")
		)
		(fp_line
			(start 0.7874 0.4064)
			(end -0.7874 0.4064)
			(stroke
				(width 0.1524)
				(type default)
			)
			(layer "F.SilkS")
		)
		(fp_line
			(start -0.7874 0.4064)
			(end -0.7874 -0.4064)
			(stroke
				(width 0.1524)
				(type default)
			)
			(layer "F.SilkS")
		)
		(fp_line
			(start -0.12065 -0.305054)
			(end -0.12065 -0.2794)
			(stroke
				(width 0.1)
				(type default)
			)
			(layer "F.Fab")
		)
		(fp_line
			(start -0.67945 -0.305054)
			(end -0.12065 -0.305054)
			(stroke
				(width 0.1)
				(type default)
			)
			(layer "F.Fab")
		)
		(fp_line
			(start 0.67945 -0.3048)
			(end 0.67945 0.3048)
			(stroke
				(width 0.1)
				(type default)
			)
			(layer "F.Fab")
		)
		(fp_line
			(start 0.12065 -0.3048)
			(end 0.67945 -0.3048)
			(stroke
				(width 0.1)
				(type default)
			)
			(layer "F.Fab")
		)
		(fp_line
			(start 0.12065 -0.2794)
			(end 0.12065 -0.3048)
			(stroke
				(width 0.1)
				(type default)
			)
			(layer "F.Fab")
		)
		(fp_line
			(start -0.12065 -0.2794)
			(end 0.12065 -0.2794)
			(stroke
				(width 0.1)
				(type default)
			)
			(layer "F.Fab")
		)
		(fp_line
			(start 0.120396 0.2794)
			(end -0.12065 0.2794)
			(stroke
				(width 0.1)
				(type default)
			)
			(layer "F.Fab")
		)
		(fp_line
			(start -0.12065 0.2794)
			(end -0.12065 0.3048)
			(stroke
				(width 0.1)
				(type default)
			)
			(layer "F.Fab")
		)
		(fp_line
			(start 0.67945 0.3048)
			(end 0.120396 0.3048)
			(stroke
				(width 0.1)
				(type default)
			)
			(layer "F.Fab")
		)
		(fp_line
			(start 0.120396 0.3048)
			(end 0.120396 0.2794)
			(stroke
				(width 0.1)
				(type default)
			)
			(layer "F.Fab")
		)
		(fp_line
			(start -0.12065 0.3048)
			(end -0.67945 0.3048)
			(stroke
				(width 0.1)
				(type default)
			)
			(layer "F.Fab")
		)
		(fp_line
			(start -0.67945 0.3048)
			(end -0.67945 -0.305054)
			(stroke
				(width 0.1)
				(type default)
			)
			(layer "F.Fab")
		)
		(pad "1" smd circle
			(at -0.40005 0 90)
			(size 0 0)
			(layers "F.Cu" "F.Mask" "F.Paste")
			(net "PVCCIN_CPU0")
		)
		(pad "2" smd circle
			(at 0.40005 0 90)
			(size 0 0)
			(layers "F.Cu" "F.Mask" "F.Paste")
			(net "GND")
		)
	)
	(footprint ""
		(layer "F.Cu")
		(at 79.666084 -347.930978)
		(property "Reference" "PR286"
			(at 0 0 0)
			(layer "F.SilkS")
			(hide yes)
			(effects
				(font
					(size 1.27 1.27)
				)
			)
		)
		(property "Value" ""
			(at 0 0 0)
			(layer "F.Fab")
			(effects
				(font
					(size 1.27 1.27)
				)
			)
		)
		(duplicate_pad_numbers_are_jumpers no)
		(fp_line
			(start -0.7874 -0.4064)
			(end 0.7874 -0.4064)
			(stroke
				(width 0.1524)
				(type default)
			)
			(layer "F.SilkS")
		)
		(fp_line
			(start -0.7874 0.4064)
			(end -0.7874 -0.4064)
			(stroke
				(width 0.1524)
				(type default)
			)
			(layer "F.SilkS")
		)
		(fp_line
			(start 0.7874 -0.4064)
			(end 0.7874 0.4064)
			(stroke
				(width 0.1524)
				(type default)
			)
			(layer "F.SilkS")
		)
		(fp_line
			(start 0.7874 0.4064)
			(end -0.7874 0.4064)
			(stroke
				(width 0.1524)
				(type default)
			)
			(layer "F.SilkS")
		)
		(fp_line
			(start -0.67945 -0.305054)
			(end -0.12065 -0.305054)
			(stroke
				(width 0.1)
				(type default)
			)
			(layer "F.Fab")
		)
		(fp_line
			(start -0.67945 0.3048)
			(end -0.67945 -0.305054)
			(stroke
				(width 0.1)
				(type default)
			)
			(layer "F.Fab")
		)
		(fp_line
			(start -0.12065 -0.305054)
			(end -0.12065 -0.2794)
			(stroke
				(width 0.1)
				(type default)
			)
			(layer "F.Fab")
		)
		(fp_line
			(start -0.12065 -0.2794)
			(end 0.12065 -0.2794)
			(stroke
				(width 0.1)
				(type default)
			)
			(layer "F.Fab")
		)
		(fp_line
			(start -0.12065 0.2794)
			(end -0.12065 0.3048)
			(stroke
				(width 0.1)
				(type default)
			)
			(layer "F.Fab")
		)
		(fp_line
			(start -0.12065 0.3048)
			(end -0.67945 0.3048)
			(stroke
				(width 0.1)
				(type default)
			)
			(layer "F.Fab")
		)
		(fp_line
			(start 0.120396 0.2794)
			(end -0.12065 0.2794)
			(stroke
				(width 0.1)
				(type default)
			)
			(layer "F.Fab")
		)
		(fp_line
			(start 0.120396 0.3048)
			(end 0.120396 0.2794)
			(stroke
				(width 0.1)
				(type default)
			)
			(layer "F.Fab")
		)
		(fp_line
			(start 0.12065 -0.3048)
			(end 0.67945 -0.3048)
			(stroke
				(width 0.1)
				(type default)
			)
			(layer "F.Fab")
		)
		(fp_line
			(start 0.12065 -0.2794)
			(end 0.12065 -0.3048)
			(stroke
				(width 0.1)
				(type default)
			)
			(layer "F.Fab")
		)
		(fp_line
			(start 0.67945 -0.3048)
			(end 0.67945 0.3048)
			(stroke
				(width 0.1)
				(type default)
			)
			(layer "F.Fab")
		)
		(fp_line
			(start 0.67945 0.3048)
			(end 0.120396 0.3048)
			(stroke
				(width 0.1)
				(type default)
			)
			(layer "F.Fab")
		)
		(pad "1" smd circle
			(at -0.40005 0)
			(size 0 0)
			(layers "F.Cu" "F.Mask" "F.Paste")
			(net "PVCCIN_CPU1_LSET7")
		)
		(pad "2" smd circle
			(at 0.40005 0)
			(size 0 0)
			(layers "F.Cu" "F.Mask" "F.Paste")
			(net "GND")
		)
	)
)
